(kicad_pcb
	(version 20260206)
	(generator "pcbnew")
	(generator_version "10.0")
	(general
		(thickness 1.6)
		(legacy_teardrops no)
	)
	(paper "A4")
	(title_block
		(title "04192023_DAF0TMB3IC0_F0TG_MB_C_brd_V02_OCP.brd")
		(comment 1 "Grand Teton / footprints 5509-5515 of 8354")
	)
	(layers
		(0 "F.Cu" signal "TOP")
		(4 "In1.Cu" signal "GND")
		(6 "In2.Cu" signal "IN1")
		(8 "In3.Cu" signal "GND1")
		(10 "In4.Cu" signal "IN2")
		(12 "In5.Cu" signal "GND2")
		(14 "In6.Cu" signal "IN3")
		(16 "In7.Cu" signal "GND3")
		(18 "In8.Cu" signal "VCC")
		(20 "In9.Cu" signal "VCC1")
		(22 "In10.Cu" signal "GND4")
		(24 "In11.Cu" signal "IN4")
		(26 "In12.Cu" signal "GND5")
		(28 "In13.Cu" signal "IN5")
		(30 "In14.Cu" signal "GND6")
		(32 "In15.Cu" signal "IN6")
		(34 "In16.Cu" signal "GND7")
		(2 "B.Cu" signal "BOTTOM")
		(9 "F.Adhes" user "F.Adhesive")
		(11 "B.Adhes" user "B.Adhesive")
		(13 "F.Paste" user "Package Geometry/Pastemask Top")
		(15 "B.Paste" user "Package Geometry/Pastemask Bottom")
		(5 "F.SilkS" user "Ref Des/Silkscreen Top")
		(7 "B.SilkS" user "Ref Des/Silkscreen Bottom")
		(1 "F.Mask" user "Board Geometry/Soldermask Top")
		(3 "B.Mask" user "Board Geometry/Soldermask Bottom")
		(17 "Dwgs.User" user "User.Drawings")
		(19 "Cmts.User" user "User.Comments")
		(21 "Eco1.User" user "User.Eco1")
		(23 "Eco2.User" user "User.Eco2")
		(25 "Edge.Cuts" user "Board Geometry/Outline")
		(27 "Margin" user)
		(31 "F.CrtYd" user "Package Geometry/Place Bound Top")
		(29 "B.CrtYd" user "Package Geometry/Place Bound Bottom")
		(35 "F.Fab" user "Ref Des/Assembly Top")
		(33 "B.Fab" user "Ref Des/Assembly Bottom")
	)
	(footprint ""
		(layer "B.Cu")
		(at 235.077 -231.648 -90)
		(property "Reference" "R369"
			(at 0 0 90)
			(layer "B.SilkS")
			(hide yes)
			(effects
				(font
					(size 1.27 1.27)
				)
				(justify mirror)
			)
		)
		(property "Value" ""
			(at 0 0 90)
			(layer "B.Fab")
			(effects
				(font
					(size 1.27 1.27)
				)
				(justify mirror)
			)
		)
		(duplicate_pad_numbers_are_jumpers no)
		(fp_line
			(start -0.7874 0.4064)
			(end 0.7874 0.4064)
			(stroke
				(width 0.1524)
				(type default)
			)
			(layer "B.SilkS")
		)
		(fp_line
			(start 0.7874 0.4064)
			(end 0.7874 -0.4064)
			(stroke
				(width 0.1524)
				(type default)
			)
			(layer "B.SilkS")
		)
		(fp_line
			(start -0.7874 -0.4064)
			(end -0.7874 0.4064)
			(stroke
				(width 0.1524)
				(type default)
			)
			(layer "B.SilkS")
		)
		(fp_line
			(start 0.7874 -0.4064)
			(end -0.7874 -0.4064)
			(stroke
				(width 0.1524)
				(type default)
			)
			(layer "B.SilkS")
		)
		(fp_line
			(start -0.67945 0.3048)
			(end -0.120396 0.3048)
			(stroke
				(width 0.1)
				(type default)
			)
			(layer "B.Fab")
		)
		(fp_line
			(start -0.120396 0.3048)
			(end -0.120396 0.2794)
			(stroke
				(width 0.1)
				(type default)
			)
			(layer "B.Fab")
		)
		(fp_line
			(start 0.12065 0.3048)
			(end 0.67945 0.3048)
			(stroke
				(width 0.1)
				(type default)
			)
			(layer "B.Fab")
		)
		(fp_line
			(start 0.67945 0.3048)
			(end 0.67945 -0.305054)
			(stroke
				(width 0.1)
				(type default)
			)
			(layer "B.Fab")
		)
		(fp_line
			(start -0.120396 0.2794)
			(end 0.12065 0.2794)
			(stroke
				(width 0.1)
				(type default)
			)
			(layer "B.Fab")
		)
		(fp_line
			(start 0.12065 0.2794)
			(end 0.12065 0.3048)
			(stroke
				(width 0.1)
				(type default)
			)
			(layer "B.Fab")
		)
		(fp_line
			(start -0.12065 -0.2794)
			(end -0.12065 -0.3048)
			(stroke
				(width 0.1)
				(type default)
			)
			(layer "B.Fab")
		)
		(fp_line
			(start 0.12065 -0.2794)
			(end -0.12065 -0.2794)
			(stroke
				(width 0.1)
				(type default)
			)
			(layer "B.Fab")
		)
		(fp_line
			(start -0.67945 -0.3048)
			(end -0.67945 0.3048)
			(stroke
				(width 0.1)
				(type default)
			)
			(layer "B.Fab")
		)
		(fp_line
			(start -0.12065 -0.3048)
			(end -0.67945 -0.3048)
			(stroke
				(width 0.1)
				(type default)
			)
			(layer "B.Fab")
		)
		(fp_line
			(start 0.12065 -0.305054)
			(end 0.12065 -0.2794)
			(stroke
				(width 0.1)
				(type default)
			)
			(layer "B.Fab")
		)
		(fp_line
			(start 0.67945 -0.305054)
			(end 0.12065 -0.305054)
			(stroke
				(width 0.1)
				(type default)
			)
			(layer "B.Fab")
		)
		(pad "1" smd circle
			(at 0.40005 0 90)
			(size 0 0)
			(layers "B.Cu" "B.Mask" "B.Paste")
			(net "PVDD18_S5_P1")
		)
		(pad "2" smd circle
			(at -0.40005 0 90)
			(size 0 0)
			(layers "B.Cu" "B.Mask" "B.Paste")
			(net "SMB_CPU1_SEC_SDA")
		)
	)
	(footprint ""
		(layer "B.Cu")
		(at 391.636758 -203.50099)
		(property "Reference" "R6084"
			(at 0 0 0)
			(layer "B.SilkS")
			(hide yes)
			(effects
				(font
					(size 1.27 1.27)
				)
				(justify mirror)
			)
		)
		(property "Value" ""
			(at 0 0 0)
			(layer "B.Fab")
			(effects
				(font
					(size 1.27 1.27)
				)
				(justify mirror)
			)
		)
		(duplicate_pad_numbers_are_jumpers no)
		(fp_line
			(start -0.7874 -0.4064)
			(end -0.7874 0.4064)
			(stroke
				(width 0.1524)
				(type default)
			)
			(layer "B.SilkS")
		)
		(fp_line
			(start -0.7874 0.4064)
			(end 0.7874 0.4064)
			(stroke
				(width 0.1524)
				(type default)
			)
			(layer "B.SilkS")
		)
		(fp_line
			(start 0.7874 -0.4064)
			(end -0.7874 -0.4064)
			(stroke
				(width 0.1524)
				(type default)
			)
			(layer "B.SilkS")
		)
		(fp_line
			(start 0.7874 0.4064)
			(end 0.7874 -0.4064)
			(stroke
				(width 0.1524)
				(type default)
			)
			(layer "B.SilkS")
		)
		(fp_line
			(start -0.67945 -0.3048)
			(end -0.67945 0.3048)
			(stroke
				(width 0.1)
				(type default)
			)
			(layer "B.Fab")
		)
		(fp_line
			(start -0.67945 0.3048)
			(end -0.120396 0.3048)
			(stroke
				(width 0.1)
				(type default)
			)
			(layer "B.Fab")
		)
		(fp_line
			(start -0.12065 -0.3048)
			(end -0.67945 -0.3048)
			(stroke
				(width 0.1)
				(type default)
			)
			(layer "B.Fab")
		)
		(fp_line
			(start -0.12065 -0.2794)
			(end -0.12065 -0.3048)
			(stroke
				(width 0.1)
				(type default)
			)
			(layer "B.Fab")
		)
		(fp_line
			(start -0.120396 0.2794)
			(end 0.12065 0.2794)
			(stroke
				(width 0.1)
				(type default)
			)
			(layer "B.Fab")
		)
		(fp_line
			(start -0.120396 0.3048)
			(end -0.120396 0.2794)
			(stroke
				(width 0.1)
				(type default)
			)
			(layer "B.Fab")
		)
		(fp_line
			(start 0.12065 -0.305054)
			(end 0.12065 -0.2794)
			(stroke
				(width 0.1)
				(type default)
			)
			(layer "B.Fab")
		)
		(fp_line
			(start 0.12065 -0.2794)
			(end -0.12065 -0.2794)
			(stroke
				(width 0.1)
				(type default)
			)
			(layer "B.Fab")
		)
		(fp_line
			(start 0.12065 0.2794)
			(end 0.12065 0.3048)
			(stroke
				(width 0.1)
				(type default)
			)
			(layer "B.Fab")
		)
		(fp_line
			(start 0.12065 0.3048)
			(end 0.67945 0.3048)
			(stroke
				(width 0.1)
				(type default)
			)
			(layer "B.Fab")
		)
		(fp_line
			(start 0.67945 -0.305054)
			(end 0.12065 -0.305054)
			(stroke
				(width 0.1)
				(type default)
			)
			(layer "B.Fab")
		)
		(fp_line
			(start 0.67945 0.3048)
			(end 0.67945 -0.305054)
			(stroke
				(width 0.1)
				(type default)
			)
			(layer "B.Fab")
		)
		(pad "1" smd circle
			(at 0.40005 0 180)
			(size 0 0)
			(layers "B.Cu" "B.Mask" "B.Paste")
			(net "PVDD11_S3_P0")
		)
		(pad "2" smd circle
			(at -0.40005 0 180)
			(size 0 0)
			(layers "B.Cu" "B.Mask" "B.Paste")
			(net "SMB_CPU0_3_SDA")
		)
	)
	(footprint ""
		(layer "B.Cu")
		(at 361.255056 -177.894996 -90)
		(property "Reference" "PC487_1"
			(at 0 0 90)
			(layer "B.SilkS")
			(hide yes)
			(effects
				(font
					(size 1.27 1.27)
				)
				(justify mirror)
			)
		)
		(property "Value" ""
			(at 0 0 90)
			(layer "B.Fab")
			(effects
				(font
					(size 1.27 1.27)
				)
				(justify mirror)
			)
		)
		(duplicate_pad_numbers_are_jumpers no)
		(fp_line
			(start -1.524 0.762)
			(end 1.524 0.762)
			(stroke
				(width 0.1524)
				(type default)
			)
			(layer "B.SilkS")
		)
		(fp_line
			(start 1.524 0.762)
			(end 1.524 -0.762)
			(stroke
				(width 0.1524)
				(type default)
			)
			(layer "B.SilkS")
		)
		(fp_line
			(start -1.524 -0.762)
			(end -1.524 0.762)
			(stroke
				(width 0.1524)
				(type default)
			)
			(layer "B.SilkS")
		)
		(fp_line
			(start 1.524 -0.762)
			(end -1.524 -0.762)
			(stroke
				(width 0.1524)
				(type default)
			)
			(layer "B.SilkS")
		)
		(fp_line
			(start -1.1049 0.724916)
			(end -1.1049 -0.724916)
			(stroke
				(width 0.1)
				(type default)
			)
			(layer "B.Fab")
		)
		(fp_line
			(start 1.1049 0.724916)
			(end -1.1049 0.724916)
			(stroke
				(width 0.1)
				(type default)
			)
			(layer "B.Fab")
		)
		(fp_line
			(start -1.1049 -0.724916)
			(end 1.1049 -0.724916)
			(stroke
				(width 0.1)
				(type default)
			)
			(layer "B.Fab")
		)
		(fp_line
			(start 1.1049 -0.724916)
			(end 1.1049 0.724916)
			(stroke
				(width 0.1)
				(type default)
			)
			(layer "B.Fab")
		)
		(pad "1" smd rect
			(at 0.889 0 270)
			(size 1.016 1.27)
			(layers "B.Cu" "B.Mask" "B.Paste")
			(net "SW_P12V_AUX_PVDDCR_CPU0_P0_FLT")
		)
		(pad "2" smd rect
			(at -0.889 0 270)
			(size 1.016 1.27)
			(layers "B.Cu" "B.Mask" "B.Paste")
			(net "GND")
		)
	)
	(footprint ""
		(layer "B.Cu")
		(at 508.971042 -306.911248 90)
		(property "Reference" "X9005"
			(at 4.62026 -1.55829 90)
			(unlocked yes)
			(layer "B.SilkS")
			(effects
				(font
					(size 0.7874 0.5842)
					(thickness 0.1524)
				)
				(justify left mirror)
			)
		)
		(property "Value" ""
			(at 0 0 90)
			(layer "B.Fab")
			(effects
				(font
					(size 1.27 1.27)
				)
				(justify mirror)
			)
		)
		(property "User Part Number" "N_A"
			(at -1.30175 1.27 0)
			(unlocked yes)
			(layer "Cmts.User")
			(hide yes)
			(effects
				(font
					(size 0.635 0.4064)
					(thickness 0.1524)
				)
				(justify mirror)
			)
		)
		(property "Device Type" "TP_TDR_4P_FTS_TH-TP_TDR_4P_DIP,EMPTY,TP15"
			(at -1.30175 1.27 0)
			(unlocked yes)
			(layer "B.Fab")
			(hide yes)
			(effects
				(font
					(size 0.635 0.4064)
					(thickness 0.1524)
				)
				(justify mirror)
			)
		)
		(duplicate_pad_numbers_are_jumpers no)
		(fp_line
			(start 0 -1.27)
			(end 0 -0.635)
			(stroke
				(width 0.1524)
				(type default)
			)
			(layer "B.SilkS")
		)
		(fp_line
			(start -2.54 -1.27)
			(end 0 -1.27)
			(stroke
				(width 0.1524)
				(type default)
			)
			(layer "B.SilkS")
		)
		(fp_line
			(start -2.54 -1.1303)
			(end -2.54 -1.27)
			(stroke
				(width 0.1524)
				(type default)
			)
			(layer "B.SilkS")
		)
		(fp_line
			(start 0 0.635)
			(end 0 1.905)
			(stroke
				(width 0.1524)
				(type default)
			)
			(layer "B.SilkS")
		)
		(fp_line
			(start -2.54 1.4097)
			(end -2.54 1.1303)
			(stroke
				(width 0.1524)
				(type default)
			)
			(layer "B.SilkS")
		)
		(fp_line
			(start 0 3.175)
			(end 0 3.81)
			(stroke
				(width 0.1524)
				(type default)
			)
			(layer "B.SilkS")
		)
		(fp_line
			(start 0 3.81)
			(end -2.54 3.81)
			(stroke
				(width 0.1524)
				(type default)
			)
			(layer "B.SilkS")
		)
		(fp_line
			(start -2.54 3.81)
			(end -2.54 3.6703)
			(stroke
				(width 0.1524)
				(type default)
			)
			(layer "B.SilkS")
		)
		(fp_poly
			(pts
				(xy 0.761746 0) (xy 2.285746 -0.762) (xy 2.285746 0.762)
			)
			(stroke
				(width 0)
				(type default)
			)
			(fill yes)
			(layer "B.SilkS")
		)
		(fp_line
			(start 0 -1.27)
			(end 0 3.81)
			(stroke
				(width 0.1)
				(type default)
			)
			(layer "B.Fab")
		)
		(fp_line
			(start -2.54 -1.27)
			(end 0 -1.27)
			(stroke
				(width 0.1)
				(type default)
			)
			(layer "B.Fab")
		)
		(fp_line
			(start 0 3.81)
			(end -2.54 3.81)
			(stroke
				(width 0.1)
				(type default)
			)
			(layer "B.Fab")
		)
		(fp_line
			(start -2.54 3.81)
			(end -2.54 -1.27)
			(stroke
				(width 0.1)
				(type default)
			)
			(layer "B.Fab")
		)
		(fp_poly
			(pts
				(xy 0.761746 0) (xy 2.285746 -0.762) (xy 2.285746 0.762)
			)
			(stroke
				(width 0)
				(type default)
			)
			(fill yes)
			(layer "B.Fab")
		)
		(pad "1" thru_hole circle
			(at 0 0 270)
			(size 1.0033 1.0033)
			(drill 0.249936)
			(layers "*.Cu" "*.Mask")
			(remove_unused_layers no)
			(net "TDR_DIFF_85_NECK_IN4_DP")
			(clearance 0.10795)
			(padstack
				(mode front_inner_back)
				(layer "Inner"
					(shape circle)
					(size 0.8001 0.8001)
					(clearance 0.1524)
				)
				(layer "B.Cu"
					(shape circle)
					(size 1.0033 1.0033)
					(thermal_gap 0.10795)
					(clearance 0.10795)
				)
			)
		)
		(pad "2" thru_hole circle
			(at -2.54 0 270)
			(size 1.9939 1.9939)
			(drill 0.249936)
			(layers "*.Cu" "*.Mask")
			(remove_unused_layers no)
			(net "T1_GND")
			(clearance 0.10795)
			(padstack
				(mode front_inner_back)
				(layer "Inner"
					(shape circle)
					(size 0.8001 0.8001)
					(clearance 0.1524)
				)
				(layer "B.Cu"
					(shape circle)
					(size 1.9939 1.9939)
					(thermal_gap 0.10795)
					(clearance 0.10795)
				)
			)
		)
		(pad "3" thru_hole circle
			(at -2.54 2.54 270)
			(size 1.9939 1.9939)
			(drill 0.249936)
			(layers "*.Cu" "*.Mask")
			(remove_unused_layers no)
			(net "T1_GND")
			(clearance 0.10795)
			(padstack
				(mode front_inner_back)
				(layer "Inner"
					(shape circle)
					(size 0.8001 0.8001)
					(clearance 0.1524)
				)
				(layer "B.Cu"
					(shape circle)
					(size 1.9939 1.9939)
					(thermal_gap 0.10795)
					(clearance 0.10795)
				)
			)
		)
		(pad "4" thru_hole circle
			(at 0 2.54 270)
			(size 1.0033 1.0033)
			(drill 0.249936)
			(layers "*.Cu" "*.Mask")
			(remove_unused_layers no)
			(net "TDR_DIFF_85_NECK_IN4_DN")
			(clearance 0.10795)
			(padstack
				(mode front_inner_back)
				(layer "Inner"
					(shape circle)
					(size 0.8001 0.8001)
					(clearance 0.1524)
				)
				(layer "B.Cu"
					(shape circle)
					(size 1.0033 1.0033)
					(thermal_gap 0.10795)
					(clearance 0.10795)
				)
			)
		)
	)
	(footprint ""
		(layer "B.Cu")
		(at 374.715278 -137.789158 -90)
		(property "Reference" "R8309"
			(at 0 0 90)
			(layer "B.SilkS")
			(hide yes)
			(effects
				(font
					(size 1.27 1.27)
				)
				(justify mirror)
			)
		)
		(property "Value" ""
			(at 0 0 90)
			(layer "B.Fab")
			(effects
				(font
					(size 1.27 1.27)
				)
				(justify mirror)
			)
		)
		(duplicate_pad_numbers_are_jumpers no)
		(fp_line
			(start -0.7874 0.4064)
			(end 0.7874 0.4064)
			(stroke
				(width 0.1524)
				(type default)
			)
			(layer "B.SilkS")
		)
		(fp_line
			(start 0.7874 0.4064)
			(end 0.7874 -0.4064)
			(stroke
				(width 0.1524)
				(type default)
			)
			(layer "B.SilkS")
		)
		(fp_line
			(start -0.7874 -0.4064)
			(end -0.7874 0.4064)
			(stroke
				(width 0.1524)
				(type default)
			)
			(layer "B.SilkS")
		)
		(fp_line
			(start 0.7874 -0.4064)
			(end -0.7874 -0.4064)
			(stroke
				(width 0.1524)
				(type default)
			)
			(layer "B.SilkS")
		)
		(fp_line
			(start -0.67945 0.3048)
			(end -0.120396 0.3048)
			(stroke
				(width 0.1)
				(type default)
			)
			(layer "B.Fab")
		)
		(fp_line
			(start -0.120396 0.3048)
			(end -0.120396 0.2794)
			(stroke
				(width 0.1)
				(type default)
			)
			(layer "B.Fab")
		)
		(fp_line
			(start 0.12065 0.3048)
			(end 0.67945 0.3048)
			(stroke
				(width 0.1)
				(type default)
			)
			(layer "B.Fab")
		)
		(fp_line
			(start 0.67945 0.3048)
			(end 0.67945 -0.305054)
			(stroke
				(width 0.1)
				(type default)
			)
			(layer "B.Fab")
		)
		(fp_line
			(start -0.120396 0.2794)
			(end 0.12065 0.2794)
			(stroke
				(width 0.1)
				(type default)
			)
			(layer "B.Fab")
		)
		(fp_line
			(start 0.12065 0.2794)
			(end 0.12065 0.3048)
			(stroke
				(width 0.1)
				(type default)
			)
			(layer "B.Fab")
		)
		(fp_line
			(start -0.12065 -0.2794)
			(end -0.12065 -0.3048)
			(stroke
				(width 0.1)
				(type default)
			)
			(layer "B.Fab")
		)
		(fp_line
			(start 0.12065 -0.2794)
			(end -0.12065 -0.2794)
			(stroke
				(width 0.1)
				(type default)
			)
			(layer "B.Fab")
		)
		(fp_line
			(start -0.67945 -0.3048)
			(end -0.67945 0.3048)
			(stroke
				(width 0.1)
				(type default)
			)
			(layer "B.Fab")
		)
		(fp_line
			(start -0.12065 -0.3048)
			(end -0.67945 -0.3048)
			(stroke
				(width 0.1)
				(type default)
			)
			(layer "B.Fab")
		)
		(fp_line
			(start 0.12065 -0.305054)
			(end 0.12065 -0.2794)
			(stroke
				(width 0.1)
				(type default)
			)
			(layer "B.Fab")
		)
		(fp_line
			(start 0.67945 -0.305054)
			(end 0.12065 -0.305054)
			(stroke
				(width 0.1)
				(type default)
			)
			(layer "B.Fab")
		)
		(pad "1" smd circle
			(at 0.40005 0 90)
			(size 0 0)
			(layers "B.Cu" "B.Mask" "B.Paste")
			(net "SMB_SCM_2_R3_SDA")
		)
		(pad "2" smd circle
			(at -0.40005 0 90)
			(size 0 0)
			(layers "B.Cu" "B.Mask" "B.Paste")
			(net "PVDDCR_CPU0_P0_PMSDA_R")
		)
	)
	(footprint ""
		(layer "B.Cu")
		(at 305.423316 -425.6532 180)
		(property "Reference" "R1439"
			(at 0 0 0)
			(layer "B.SilkS")
			(hide yes)
			(effects
				(font
					(size 1.27 1.27)
				)
				(justify mirror)
			)
		)
		(property "Value" ""
			(at 0 0 0)
			(layer "B.Fab")
			(effects
				(font
					(size 1.27 1.27)
				)
				(justify mirror)
			)
		)
		(duplicate_pad_numbers_are_jumpers no)
		(fp_line
			(start 0.32512 0.175006)
			(end 0.32512 -0.175006)
			(stroke
				(width 0.1)
				(type default)
			)
			(layer "B.Fab")
		)
		(fp_line
			(start 0.32512 -0.175006)
			(end -0.32512 -0.175006)
			(stroke
				(width 0.1)
				(type default)
			)
			(layer "B.Fab")
		)
		(fp_line
			(start -0.32512 0.175006)
			(end 0.32512 0.175006)
			(stroke
				(width 0.1)
				(type default)
			)
			(layer "B.Fab")
		)
		(fp_line
			(start -0.32512 -0.175006)
			(end -0.32512 0.175006)
			(stroke
				(width 0.1)
				(type default)
			)
			(layer "B.Fab")
		)
		(pad "1" smd rect
			(at 0.2667 0)
			(size 0.3048 0.381)
			(layers "B.Cu" "B.Mask" "B.Paste")
			(net "P1V8_CPU0_RT_1D")
		)
		(pad "2" smd rect
			(at -0.2667 0 180)
			(size 0.3048 0.381)
			(layers "B.Cu" "B.Mask" "B.Paste")
			(net "JTAG_TMS_RT_CPU0_P0")
		)
	)
	(footprint ""
		(layer "B.Cu")
		(at 157.226 -416.1536 180)
		(property "Reference" "R1469"
			(at 0 0 0)
			(layer "B.SilkS")
			(hide yes)
			(effects
				(font
					(size 1.27 1.27)
				)
				(justify mirror)
			)
		)
		(property "Value" ""
			(at 0 0 0)
			(layer "B.Fab")
			(effects
				(font
					(size 1.27 1.27)
				)
				(justify mirror)
			)
		)
		(duplicate_pad_numbers_are_jumpers no)
		(fp_line
			(start 0.32512 0.175006)
			(end 0.32512 -0.175006)
			(stroke
				(width 0.1)
				(type default)
			)
			(layer "B.Fab")
		)
		(fp_line
			(start 0.32512 -0.175006)
			(end -0.32512 -0.175006)
			(stroke
				(width 0.1)
				(type default)
			)
			(layer "B.Fab")
		)
		(fp_line
			(start -0.32512 0.175006)
			(end 0.32512 0.175006)
			(stroke
				(width 0.1)
				(type default)
			)
			(layer "B.Fab")
		)
		(fp_line
			(start -0.32512 -0.175006)
			(end -0.32512 0.175006)
			(stroke
				(width 0.1)
				(type default)
			)
			(layer "B.Fab")
		)
		(pad "1" smd rect
			(at 0.2667 0)
			(size 0.3048 0.381)
			(layers "B.Cu" "B.Mask" "B.Paste")
			(net "P1V8_CPU1_RT_1D")
		)
		(pad "2" smd rect
			(at -0.2667 0 180)
			(size 0.3048 0.381)
			(layers "B.Cu" "B.Mask" "B.Paste")
			(net "SMB_RT_CPU1_P2_ROM_MUX_1D_SCL")
		)
	)
)
